# S9S_MB_2U (Grand Teton) — schematic netlist excerpt (pin names and nets, part order shuffled) for the footprints in the layout excerpt that follows; sources: Cadence DE-HDL packaged netlist, KiCad conversion of 03242023_DA0F0TMBIJ0_F0T_Motherboard_J_brd_V01_OCP.brd

R3355  Q_RES  0 5% CHIP  pkg 0402LF  page 207 : A = CLK_100M_GPU_2_R_DN ; B = CLK_100M_GPU_2_DN
R3433  Q_RES  4.7K 5% CHIP  pkg 0402LF  page 147 : A = P3V3_AUX ; B = GPU_BASE_HMC_READY_N

(kicad_pcb
	(version 20260206)
	(generator "pcbnew")
	(generator_version "10.0")
	(general
		(thickness 1.6)
		(legacy_teardrops no)
	)
	(paper "A4")
	(title_block
		(title "03242023_DA0F0TMBIJ0_F0T_Motherboard_J_brd_V01_OCP.brd")
		(comment 1 "Grand Teton / footprints 385-386 of 6105")
	)
	(layers
		(0 "F.Cu" signal "TOP")
		(4 "In1.Cu" signal "GND")
		(6 "In2.Cu" signal "IN1")
		(8 "In3.Cu" signal "GND1")
		(10 "In4.Cu" signal "IN2")
		(12 "In5.Cu" signal "GND2")
		(14 "In6.Cu" signal "IN3")
		(16 "In7.Cu" signal "GND3")
		(18 "In8.Cu" signal "VCC")
		(20 "In9.Cu" signal "VCC1")
		(22 "In10.Cu" signal "GND4")
		(24 "In11.Cu" signal "IN4")
		(26 "In12.Cu" signal "GND5")
		(28 "In13.Cu" signal "IN5")
		(30 "In14.Cu" signal "GND6")
		(32 "In15.Cu" signal "IN6")
		(34 "In16.Cu" signal "GND7")
		(2 "B.Cu" signal "BOTTOM")
		(9 "F.Adhes" user "F.Adhesive")
		(11 "B.Adhes" user "B.Adhesive")
		(13 "F.Paste" user "Package Geometry/Pastemask Top")
		(15 "B.Paste" user "Package Geometry/Pastemask Bottom")
		(5 "F.SilkS" user "Ref Des/Silkscreen Top")
		(7 "B.SilkS" user "Ref Des/Silkscreen Bottom")
		(1 "F.Mask" user "Board Geometry/Soldermask Top")
		(3 "B.Mask" user "Board Geometry/Soldermask Bottom")
		(17 "Dwgs.User" user "User.Drawings")
		(19 "Cmts.User" user "User.Comments")
		(21 "Eco1.User" user "User.Eco1")
		(23 "Eco2.User" user "User.Eco2")
		(25 "Edge.Cuts" user "Board Geometry/Outline")
		(27 "Margin" user)
		(31 "F.CrtYd" user "Package Geometry/Place Bound Top")
		(29 "B.CrtYd" user "Package Geometry/Place Bound Bottom")
		(35 "F.Fab" user "Ref Des/Assembly Top")
		(33 "B.Fab" user "Ref Des/Assembly Bottom")
	)
	(footprint ""
		(layer "F.Cu")
		(at 106.70921 -412.671768 180)
		(property "Reference" "R3355"
			(at 0 0 180)
			(layer "F.SilkS")
			(hide yes)
			(effects
				(font
					(size 1.27 1.27)
				)
			)
		)
		(property "Value" ""
			(at 0 0 180)
			(layer "F.Fab")
			(effects
				(font
					(size 1.27 1.27)
				)
			)
		)
		(duplicate_pad_numbers_are_jumpers no)
		(fp_line
			(start 0.7874 -0.4064)
			(end 0.7874 -0.00762)
			(stroke
				(width 0.1524)
				(type default)
			)
			(layer "F.SilkS")
		)
		(fp_line
			(start 0.43307 0.4064)
			(end -0.49149 0.4064)
			(stroke
				(width 0.1524)
				(type default)
			)
			(layer "F.SilkS")
		)
		(fp_line
			(start -0.7874 0.05842)
			(end -0.7874 -0.4064)
			(stroke
				(width 0.1524)
				(type default)
			)
			(layer "F.SilkS")
		)
		(fp_line
			(start -0.7874 -0.4064)
			(end 0.7874 -0.4064)
			(stroke
				(width 0.1524)
				(type default)
			)
			(layer "F.SilkS")
		)
		(fp_line
			(start 0.67945 0.3048)
			(end 0.120396 0.3048)
			(stroke
				(width 0.1)
				(type default)
			)
			(layer "F.Fab")
		)
		(fp_line
			(start 0.67945 -0.3048)
			(end 0.67945 0.3048)
			(stroke
				(width 0.1)
				(type default)
			)
			(layer "F.Fab")
		)
		(fp_line
			(start 0.12065 -0.2794)
			(end 0.12065 -0.3048)
			(stroke
				(width 0.1)
				(type default)
			)
			(layer "F.Fab")
		)
		(fp_line
			(start 0.12065 -0.3048)
			(end 0.67945 -0.3048)
			(stroke
				(width 0.1)
				(type default)
			)
			(layer "F.Fab")
		)
		(fp_line
			(start 0.120396 0.3048)
			(end 0.120396 0.2794)
			(stroke
				(width 0.1)
				(type default)
			)
			(layer "F.Fab")
		)
		(fp_line
			(start 0.120396 0.2794)
			(end -0.12065 0.2794)
			(stroke
				(width 0.1)
				(type default)
			)
			(layer "F.Fab")
		)
		(fp_line
			(start -0.12065 0.3048)
			(end -0.67945 0.3048)
			(stroke
				(width 0.1)
				(type default)
			)
			(layer "F.Fab")
		)
		(fp_line
			(start -0.12065 0.2794)
			(end -0.12065 0.3048)
			(stroke
				(width 0.1)
				(type default)
			)
			(layer "F.Fab")
		)
		(fp_line
			(start -0.12065 -0.2794)
			(end 0.12065 -0.2794)
			(stroke
				(width 0.1)
				(type default)
			)
			(layer "F.Fab")
		)
		(fp_line
			(start -0.12065 -0.305054)
			(end -0.12065 -0.2794)
			(stroke
				(width 0.1)
				(type default)
			)
			(layer "F.Fab")
		)
		(fp_line
			(start -0.67945 0.3048)
			(end -0.67945 -0.305054)
			(stroke
				(width 0.1)
				(type default)
			)
			(layer "F.Fab")
		)
		(fp_line
			(start -0.67945 -0.305054)
			(end -0.12065 -0.305054)
			(stroke
				(width 0.1)
				(type default)
			)
			(layer "F.Fab")
		)
		(pad "1" smd circle
			(at -0.40005 0 180)
			(size 0 0)
			(layers "F.Cu" "F.Mask" "F.Paste")
			(net "CLK_100M_GPU_2_R_DN")
		)
		(pad "2" smd circle
			(at 0.40005 0 180)
			(size 0 0)
			(layers "F.Cu" "F.Mask" "F.Paste")
			(net "CLK_100M_GPU_2_DN")
		)
	)
	(footprint ""
		(layer "F.Cu")
		(at 176.080928 -418.806122)
		(property "Reference" "R3433"
			(at 0 0 0)
			(layer "F.SilkS")
			(hide yes)
			(effects
				(font
					(size 1.27 1.27)
				)
			)
		)
		(property "Value" ""
			(at 0 0 0)
			(layer "F.Fab")
			(effects
				(font
					(size 1.27 1.27)
				)
			)
		)
		(duplicate_pad_numbers_are_jumpers no)
		(fp_line
			(start -0.7874 -0.4064)
			(end 0.7874 -0.4064)
			(stroke
				(width 0.1524)
				(type default)
			)
			(layer "F.SilkS")
		)
		(fp_line
			(start -0.7874 0.4064)
			(end -0.7874 -0.4064)
			(stroke
				(width 0.1524)
				(type default)
			)
			(layer "F.SilkS")
		)
		(fp_line
			(start 0.7874 -0.4064)
			(end 0.7874 0.4064)
			(stroke
				(width 0.1524)
				(type default)
			)
			(layer "F.SilkS")
		)
		(fp_line
			(start 0.7874 0.4064)
			(end -0.7874 0.4064)
			(stroke
				(width 0.1524)
				(type default)
			)
			(layer "F.SilkS")
		)
		(fp_line
			(start -0.67945 -0.305054)
			(end -0.12065 -0.305054)
			(stroke
				(width 0.1)
				(type default)
			)
			(layer "F.Fab")
		)
		(fp_line
			(start -0.67945 0.3048)
			(end -0.67945 -0.305054)
			(stroke
				(width 0.1)
				(type default)
			)
			(layer "F.Fab")
		)
		(fp_line
			(start -0.12065 -0.305054)
			(end -0.12065 -0.2794)
			(stroke
				(width 0.1)
				(type default)
			)
			(layer "F.Fab")
		)
		(fp_line
			(start -0.12065 -0.2794)
			(end 0.12065 -0.2794)
			(stroke
				(width 0.1)
				(type default)
			)
			(layer "F.Fab")
		)
		(fp_line
			(start -0.12065 0.2794)
			(end -0.12065 0.3048)
			(stroke
				(width 0.1)
				(type default)
			)
			(layer "F.Fab")
		)
		(fp_line
			(start -0.12065 0.3048)
			(end -0.67945 0.3048)
			(stroke
				(width 0.1)
				(type default)
			)
			(layer "F.Fab")
		)
		(fp_line
			(start 0.120396 0.2794)
			(end -0.12065 0.2794)
			(stroke
				(width 0.1)
				(type default)
			)
			(layer "F.Fab")
		)
		(fp_line
			(start 0.120396 0.3048)
			(end 0.120396 0.2794)
			(stroke
				(width 0.1)
				(type default)
			)
			(layer "F.Fab")
		)
		(fp_line
			(start 0.12065 -0.3048)
			(end 0.67945 -0.3048)
			(stroke
				(width 0.1)
				(type default)
			)
			(layer "F.Fab")
		)
		(fp_line
			(start 0.12065 -0.2794)
			(end 0.12065 -0.3048)
			(stroke
				(width 0.1)
				(type default)
			)
			(layer "F.Fab")
		)
		(fp_line
			(start 0.67945 -0.3048)
			(end 0.67945 0.3048)
			(stroke
				(width 0.1)
				(type default)
			)
			(layer "F.Fab")
		)
		(fp_line
			(start 0.67945 0.3048)
			(end 0.120396 0.3048)
			(stroke
				(width 0.1)
				(type default)
			)
			(layer "F.Fab")
		)
		(pad "1" smd circle
			(at -0.40005 0)
			(size 0 0)
			(layers "F.Cu" "F.Mask" "F.Paste")
			(net "P3V3_AUX")
		)
		(pad "2" smd circle
			(at 0.40005 0)
			(size 0 0)
			(layers "F.Cu" "F.Mask" "F.Paste")
			(net "GPU_BASE_HMC_READY_N")
		)
	)
)
